(kicad_pcb
	(version 20260206)
	(generator "pcbnew")
	(generator_version "10.0")
	(general
		(thickness 1.6)
		(legacy_teardrops no)
	)
	(paper "A4")
	(title_block
		(title "dpb — 14545-sa.0730WZS0815.brd")
		(comment 1 "Honey Badger (Wiwynn) / footprints 497-503 of 1066")
	)
	(layers
		(0 "F.Cu" signal "TOP")
		(4 "In1.Cu" signal "L2GND")
		(6 "In2.Cu" signal "L3")
		(8 "In3.Cu" signal "L4VCC")
		(10 "In4.Cu" signal "L5VCC")
		(12 "In5.Cu" signal "L6")
		(14 "In6.Cu" signal "L7GND")
		(2 "B.Cu" signal "BOTTOM")
		(9 "F.Adhes" user "F.Adhesive")
		(11 "B.Adhes" user "B.Adhesive")
		(13 "F.Paste" user "Package Geometry/Pastemask Top")
		(15 "B.Paste" user "Package Geometry/Pastemask Bottom")
		(5 "F.SilkS" user "Ref Des/Silkscreen Top")
		(7 "B.SilkS" user "Ref Des/Silkscreen Bottom")
		(1 "F.Mask" user "Board Geometry/Soldermask Top")
		(3 "B.Mask" user "Board Geometry/Soldermask Bottom")
		(17 "Dwgs.User" user "User.Drawings")
		(19 "Cmts.User" user "User.Comments")
		(21 "Eco1.User" user "User.Eco1")
		(23 "Eco2.User" user "User.Eco2")
		(25 "Edge.Cuts" user "Board Geometry/Outline")
		(27 "Margin" user)
		(31 "F.CrtYd" user "Package Geometry/Place Bound Top")
		(29 "B.CrtYd" user "Package Geometry/Place Bound Bottom")
		(35 "F.Fab" user "Ref Des/Assembly Top")
		(33 "B.Fab" user "Ref Des/Assembly Bottom")
	)
	(footprint ""
		(layer "F.Cu")
		(at 60.629546 -191.7827 180)
		(property "Reference" "C240"
			(at 0 0 180)
			(layer "F.SilkS")
			(hide yes)
			(effects
				(font
					(size 1.27 1.27)
				)
			)
		)
		(property "Value" "SC10U25V6KX-1GP"
			(at -0.0762 -5.1308 180)
			(unlocked yes)
			(layer "F.Fab")
			(hide yes)
			(effects
				(font
					(size 1.016 1.016)
					(thickness 0.1524)
				)
			)
		)
		(property "Device Type" "C1206H71"
			(at -0.127 -6.6548 180)
			(unlocked yes)
			(layer "F.Fab")
			(hide yes)
			(effects
				(font
					(size 1.016 1.016)
					(thickness 0.1524)
				)
			)
		)
		(duplicate_pad_numbers_are_jumpers no)
		(fp_line
			(start 1.016 2.2352)
			(end -1.016 2.2352)
			(stroke
				(width 0.1524)
				(type default)
			)
			(layer "F.SilkS")
		)
		(fp_line
			(start 1.016 0.8382)
			(end 1.016 2.2352)
			(stroke
				(width 0.1524)
				(type default)
			)
			(layer "F.SilkS")
		)
		(fp_line
			(start 1.016 -2.2352)
			(end 1.016 -0.8382)
			(stroke
				(width 0.1524)
				(type default)
			)
			(layer "F.SilkS")
		)
		(fp_line
			(start -1.016 2.2352)
			(end -1.016 0.8382)
			(stroke
				(width 0.1524)
				(type default)
			)
			(layer "F.SilkS")
		)
		(fp_line
			(start -1.016 -0.8382)
			(end -1.016 -2.2352)
			(stroke
				(width 0.1524)
				(type default)
			)
			(layer "F.SilkS")
		)
		(fp_line
			(start -1.016 -2.2352)
			(end 1.016 -2.2352)
			(stroke
				(width 0.1524)
				(type default)
			)
			(layer "F.SilkS")
		)
		(fp_rect
			(start -1.0922 2.3114)
			(end 1.0922 -2.3114)
			(stroke
				(width 0)
				(type default)
			)
			(fill no)
			(layer "F.CrtYd")
		)
		(fp_poly
			(pts
				(xy 1.0922 -2.3114) (xy 1.0922 2.3114) (xy -1.0922 2.3114) (xy -1.0922 -2.3114)
			)
			(stroke
				(width 0)
				(type default)
			)
			(fill no)
			(layer "F.Fab")
		)
		(pad "1" smd rect
			(at 0 -1.397 180)
			(size 1.651 1.27)
			(layers "F.Cu" "F.Mask" "F.Paste")
			(net "P12V_HDD8")
		)
		(pad "2" smd rect
			(at 0 1.397 180)
			(size 1.651 1.27)
			(layers "F.Cu" "F.Mask" "F.Paste")
			(net "GND")
		)
	)
	(footprint ""
		(layer "F.Cu")
		(at 164.985446 -461.933036 90)
		(property "Reference" "R364"
			(at 0 0 90)
			(layer "F.SilkS")
			(hide yes)
			(effects
				(font
					(size 1.27 1.27)
				)
			)
		)
		(property "Value" "4K7R2J-2-GP"
			(at 0.064008 -3.993896 90)
			(unlocked yes)
			(layer "F.Fab")
			(hide yes)
			(effects
				(font
					(size 1.016 1.016)
					(thickness 0.1524)
				)
			)
		)
		(property "Device Type" "R402H16"
			(at 0.064008 -5.517896 90)
			(unlocked yes)
			(layer "F.Fab")
			(hide yes)
			(effects
				(font
					(size 1.016 1.016)
					(thickness 0.1524)
				)
			)
		)
		(duplicate_pad_numbers_are_jumpers no)
		(fp_line
			(start 0.508 -0.9398)
			(end -0.508 -0.9398)
			(stroke
				(width 0.1524)
				(type default)
			)
			(layer "F.SilkS")
		)
		(fp_line
			(start -0.508 -0.9398)
			(end -0.508 0.9398)
			(stroke
				(width 0.1524)
				(type default)
			)
			(layer "F.SilkS")
		)
		(fp_rect
			(start -0.508 0.9398)
			(end 0.508 -0.9398)
			(stroke
				(width 0)
				(type default)
			)
			(fill no)
			(layer "F.CrtYd")
		)
		(fp_rect
			(start -0.508 0.9398)
			(end 0.508 -0.9398)
			(stroke
				(width 0)
				(type default)
			)
			(fill no)
			(layer "F.Fab")
		)
		(pad "1" smd custom
			(at 0 -0.4445 90)
			(size 0.1397 0.1397)
			(layers "F.Cu" "F.Mask" "F.Paste")
			(net "P3V3")
			(options
				(clearance outline)
				(anchor circle)
			)
			(primitives
				(gr_poly
					(pts
						(arc
							(start -0.1778 -0.2794)
							(mid -0.249642 -0.249642)
							(end -0.2794 -0.1778)
						)
						(arc
							(start -0.2794 0.1778)
							(mid -0.249642 0.249642)
							(end -0.1778 0.2794)
						)
						(arc
							(start 0.1778 0.2794)
							(mid 0.249642 0.249642)
							(end 0.2794 0.1778)
						)
						(arc
							(start 0.2794 -0.1778)
							(mid 0.249642 -0.249642)
							(end 0.1778 -0.2794)
						)
					)
					(width 0)
					(fill yes)
				)
			)
		)
		(pad "2" smd custom
			(at 0 0.4445 90)
			(size 0.1397 0.1397)
			(layers "F.Cu" "F.Mask" "F.Paste")
			(net "VOL_SEN_ADDR")
			(options
				(clearance outline)
				(anchor circle)
			)
			(primitives
				(gr_poly
					(pts
						(arc
							(start -0.1778 -0.2794)
							(mid -0.249642 -0.249642)
							(end -0.2794 -0.1778)
						)
						(arc
							(start -0.2794 0.1778)
							(mid -0.249642 0.249642)
							(end -0.1778 0.2794)
						)
						(arc
							(start 0.1778 0.2794)
							(mid 0.249642 0.249642)
							(end 0.2794 0.1778)
						)
						(arc
							(start 0.2794 -0.1778)
							(mid 0.249642 -0.249642)
							(end 0.1778 -0.2794)
						)
					)
					(width 0)
					(fill yes)
				)
			)
		)
	)
	(footprint ""
		(layer "F.Cu")
		(at 210.946746 -183.1467)
		(property "Reference" "C159"
			(at 0 0 0)
			(layer "F.SilkS")
			(hide yes)
			(effects
				(font
					(size 1.27 1.27)
				)
			)
		)
		(property "Value" "SC10U25V6KX-1GP"
			(at -0.0762 -5.1308 0)
			(unlocked yes)
			(layer "F.Fab")
			(hide yes)
			(effects
				(font
					(size 1.016 1.016)
					(thickness 0.1524)
				)
			)
		)
		(property "Device Type" "C1206H71"
			(at -0.127 -6.6548 0)
			(unlocked yes)
			(layer "F.Fab")
			(hide yes)
			(effects
				(font
					(size 1.016 1.016)
					(thickness 0.1524)
				)
			)
		)
		(duplicate_pad_numbers_are_jumpers no)
		(fp_line
			(start -1.016 -2.2352)
			(end 1.016 -2.2352)
			(stroke
				(width 0.1524)
				(type default)
			)
			(layer "F.SilkS")
		)
		(fp_line
			(start -1.016 -0.8382)
			(end -1.016 -2.2352)
			(stroke
				(width 0.1524)
				(type default)
			)
			(layer "F.SilkS")
		)
		(fp_line
			(start -1.016 2.2352)
			(end -1.016 0.8382)
			(stroke
				(width 0.1524)
				(type default)
			)
			(layer "F.SilkS")
		)
		(fp_line
			(start 1.016 -2.2352)
			(end 1.016 -0.8382)
			(stroke
				(width 0.1524)
				(type default)
			)
			(layer "F.SilkS")
		)
		(fp_line
			(start 1.016 0.8382)
			(end 1.016 2.2352)
			(stroke
				(width 0.1524)
				(type default)
			)
			(layer "F.SilkS")
		)
		(fp_line
			(start 1.016 2.2352)
			(end -1.016 2.2352)
			(stroke
				(width 0.1524)
				(type default)
			)
			(layer "F.SilkS")
		)
		(fp_rect
			(start -1.0922 2.3114)
			(end 1.0922 -2.3114)
			(stroke
				(width 0)
				(type default)
			)
			(fill no)
			(layer "F.CrtYd")
		)
		(fp_poly
			(pts
				(xy 1.0922 -2.3114) (xy 1.0922 2.3114) (xy -1.0922 2.3114) (xy -1.0922 -2.3114)
			)
			(stroke
				(width 0)
				(type default)
			)
			(fill no)
			(layer "F.Fab")
		)
		(pad "1" smd rect
			(at 0 -1.397)
			(size 1.651 1.27)
			(layers "F.Cu" "F.Mask" "F.Paste")
			(net "P12V_HDD3")
		)
		(pad "2" smd rect
			(at 0 1.397)
			(size 1.651 1.27)
			(layers "F.Cu" "F.Mask" "F.Paste")
			(net "GND")
		)
	)
	(footprint ""
		(layer "F.Cu")
		(at 213.5632 -86.6902 180)
		(property "Reference" "C175"
			(at 0 0 180)
			(layer "F.SilkS")
			(hide yes)
			(effects
				(font
					(size 1.27 1.27)
				)
			)
		)
		(property "Value" "SC10U25V6KX-1GP"
			(at -0.0762 -5.1308 180)
			(unlocked yes)
			(layer "F.Fab")
			(hide yes)
			(effects
				(font
					(size 1.016 1.016)
					(thickness 0.1524)
				)
			)
		)
		(property "Device Type" "C1206H71"
			(at -0.127 -6.6548 180)
			(unlocked yes)
			(layer "F.Fab")
			(hide yes)
			(effects
				(font
					(size 1.016 1.016)
					(thickness 0.1524)
				)
			)
		)
		(duplicate_pad_numbers_are_jumpers no)
		(fp_line
			(start 1.016 2.2352)
			(end -1.016 2.2352)
			(stroke
				(width 0.1524)
				(type default)
			)
			(layer "F.SilkS")
		)
		(fp_line
			(start 1.016 0.8382)
			(end 1.016 2.2352)
			(stroke
				(width 0.1524)
				(type default)
			)
			(layer "F.SilkS")
		)
		(fp_line
			(start 1.016 -2.2352)
			(end 1.016 -0.8382)
			(stroke
				(width 0.1524)
				(type default)
			)
			(layer "F.SilkS")
		)
		(fp_line
			(start -1.016 2.2352)
			(end -1.016 0.8382)
			(stroke
				(width 0.1524)
				(type default)
			)
			(layer "F.SilkS")
		)
		(fp_line
			(start -1.016 -0.8382)
			(end -1.016 -2.2352)
			(stroke
				(width 0.1524)
				(type default)
			)
			(layer "F.SilkS")
		)
		(fp_line
			(start -1.016 -2.2352)
			(end 1.016 -2.2352)
			(stroke
				(width 0.1524)
				(type default)
			)
			(layer "F.SilkS")
		)
		(fp_rect
			(start -1.0922 2.3114)
			(end 1.0922 -2.3114)
			(stroke
				(width 0)
				(type default)
			)
			(fill no)
			(layer "F.CrtYd")
		)
		(fp_poly
			(pts
				(xy 1.0922 -2.3114) (xy 1.0922 2.3114) (xy -1.0922 2.3114) (xy -1.0922 -2.3114)
			)
			(stroke
				(width 0)
				(type default)
			)
			(fill no)
			(layer "F.Fab")
		)
		(pad "1" smd rect
			(at 0 -1.397 180)
			(size 1.651 1.27)
			(layers "F.Cu" "F.Mask" "F.Paste")
			(net "P12V_HDD4")
		)
		(pad "2" smd rect
			(at 0 1.397 180)
			(size 1.651 1.27)
			(layers "F.Cu" "F.Mask" "F.Paste")
			(net "GND")
		)
	)
	(footprint ""
		(layer "F.Cu")
		(at 54.508146 -191.7827 180)
		(property "Reference" "C243"
			(at 0 0 180)
			(layer "F.SilkS")
			(hide yes)
			(effects
				(font
					(size 1.27 1.27)
				)
			)
		)
		(property "Value" "SC1U25V3KX-1-GP"
			(at 0 -2.8194 180)
			(unlocked yes)
			(layer "F.Fab")
			(hide yes)
			(effects
				(font
					(size 1.016 1.016)
					(thickness 0.1524)
				)
			)
		)
		(property "Device Type" "C603H36"
			(at 0 -4.3434 180)
			(unlocked yes)
			(layer "F.Fab")
			(hide yes)
			(effects
				(font
					(size 1.016 1.016)
					(thickness 0.1524)
				)
			)
		)
		(duplicate_pad_numbers_are_jumpers no)
		(fp_line
			(start 0.508 0)
			(end -0.508 0)
			(stroke
				(width 0.2032)
				(type default)
			)
			(layer "F.SilkS")
		)
		(fp_rect
			(start -0.5842 1.3335)
			(end 0.5842 -1.3335)
			(stroke
				(width 0)
				(type default)
			)
			(fill no)
			(layer "F.CrtYd")
		)
		(fp_rect
			(start -0.5842 1.3335)
			(end 0.5842 -1.3335)
			(stroke
				(width 0)
				(type default)
			)
			(fill no)
			(layer "F.Fab")
		)
		(pad "1" smd custom
			(at 0 -0.762 180)
			(size 0.2159 0.2159)
			(layers "F.Cu" "F.Mask" "F.Paste")
			(net "P12V_HDD8")
			(options
				(clearance outline)
				(anchor circle)
			)
			(primitives
				(gr_poly
					(pts
						(arc
							(start -0.3302 -0.4318)
							(mid -0.402042 -0.402042)
							(end -0.4318 -0.3302)
						)
						(arc
							(start -0.4318 0.3302)
							(mid -0.402042 0.402042)
							(end -0.3302 0.4318)
						)
						(arc
							(start 0.3302 0.4318)
							(mid 0.402042 0.402042)
							(end 0.4318 0.3302)
						)
						(arc
							(start 0.4318 -0.3302)
							(mid 0.402042 -0.402042)
							(end 0.3302 -0.4318)
						)
					)
					(width 0)
					(fill yes)
				)
			)
		)
		(pad "2" smd custom
			(at 0 0.762 180)
			(size 0.2159 0.2159)
			(layers "F.Cu" "F.Mask" "F.Paste")
			(net "GND")
			(options
				(clearance outline)
				(anchor circle)
			)
			(primitives
				(gr_poly
					(pts
						(arc
							(start -0.3302 -0.4318)
							(mid -0.402042 -0.402042)
							(end -0.4318 -0.3302)
						)
						(arc
							(start -0.4318 0.3302)
							(mid -0.402042 0.402042)
							(end -0.3302 0.4318)
						)
						(arc
							(start 0.3302 0.4318)
							(mid 0.402042 0.402042)
							(end 0.4318 0.3302)
						)
						(arc
							(start 0.4318 -0.3302)
							(mid 0.402042 -0.402042)
							(end 0.3302 -0.4318)
						)
					)
					(width 0)
					(fill yes)
				)
			)
		)
	)
	(footprint ""
		(layer "F.Cu")
		(at 51.561746 -22.9997 90)
		(property "Reference" "TP20"
			(at 0 0 90)
			(layer "F.SilkS")
			(hide yes)
			(effects
				(font
					(size 1.27 1.27)
				)
			)
		)
		(property "Value" "TPAD32-GP"
			(at 0 -3.166364 90)
			(unlocked yes)
			(layer "F.Fab")
			(hide yes)
			(effects
				(font
					(size 1.016 1.016)
					(thickness 0.1524)
				)
			)
		)
		(property "Device Type" "TPAD32"
			(at 0 -4.690618 90)
			(unlocked yes)
			(layer "F.Fab")
			(hide yes)
			(effects
				(font
					(size 1.016 1.016)
					(thickness 0.1524)
				)
			)
		)
		(duplicate_pad_numbers_are_jumpers no)
		(fp_poly
			(pts
				(arc
					(start 0 0.4064)
					(mid 0 -0.4064)
					(end 0 0.4064)
				)
			)
			(stroke
				(width 0)
				(type default)
			)
			(fill no)
			(layer "F.CrtYd")
		)
		(fp_poly
			(pts
				(arc
					(start 0 0.7112)
					(mid 0 -0.7112)
					(end 0 0.7112)
				)
			)
			(stroke
				(width 0)
				(type default)
			)
			(fill no)
			(layer "F.Fab")
		)
		(pad "1" smd circle
			(at 0 0 90)
			(size 0.8128 0.8128)
			(layers "F.Cu" "F.Mask" "F.Paste")
			(net "P5VB_EN")
		)
	)
	(footprint ""
		(layer "F.Cu")
		(at 59.9694 -481.4824)
		(property "Reference" "R376"
			(at 0 0 0)
			(layer "F.SilkS")
			(hide yes)
			(effects
				(font
					(size 1.27 1.27)
				)
			)
		)
		(property "Value" "0R2J-2-GP"
			(at 0.064008 -3.993896 0)
			(unlocked yes)
			(layer "F.Fab")
			(hide yes)
			(effects
				(font
					(size 1.016 1.016)
					(thickness 0.1524)
				)
			)
		)
		(property "Device Type" "R402H16"
			(at 0.064008 -5.517896 0)
			(unlocked yes)
			(layer "F.Fab")
			(hide yes)
			(effects
				(font
					(size 1.016 1.016)
					(thickness 0.1524)
				)
			)
		)
		(duplicate_pad_numbers_are_jumpers no)
		(fp_line
			(start -0.508 -0.9398)
			(end -0.508 0.9398)
			(stroke
				(width 0.1524)
				(type default)
			)
			(layer "F.SilkS")
		)
		(fp_line
			(start 0.508 -0.9398)
			(end -0.508 -0.9398)
			(stroke
				(width 0.1524)
				(type default)
			)
			(layer "F.SilkS")
		)
		(fp_rect
			(start -0.508 0.9398)
			(end 0.508 -0.9398)
			(stroke
				(width 0)
				(type default)
			)
			(fill no)
			(layer "F.CrtYd")
		)
		(fp_rect
			(start -0.508 0.9398)
			(end 0.508 -0.9398)
			(stroke
				(width 0)
				(type default)
			)
			(fill no)
			(layer "F.Fab")
		)
		(pad "1" smd custom
			(at 0 -0.4445)
			(size 0.1397 0.1397)
			(layers "F.Cu" "F.Mask" "F.Paste")
			(net "HDD_PRSNT_NET5")
			(options
				(clearance outline)
				(anchor circle)
			)
			(primitives
				(gr_poly
					(pts
						(arc
							(start -0.1778 -0.2794)
							(mid -0.249642 -0.249642)
							(end -0.2794 -0.1778)
						)
						(arc
							(start -0.2794 0.1778)
							(mid -0.249642 0.249642)
							(end -0.1778 0.2794)
						)
						(arc
							(start 0.1778 0.2794)
							(mid 0.249642 0.249642)
							(end 0.2794 0.1778)
						)
						(arc
							(start 0.2794 -0.1778)
							(mid 0.249642 -0.249642)
							(end 0.1778 -0.2794)
						)
					)
					(width 0)
					(fill yes)
				)
			)
		)
		(pad "2" smd custom
			(at 0 0.4445)
			(size 0.1397 0.1397)
			(layers "F.Cu" "F.Mask" "F.Paste")
			(net "HDD5_LED_B")
			(options
				(clearance outline)
				(anchor circle)
			)
			(primitives
				(gr_poly
					(pts
						(arc
							(start -0.1778 -0.2794)
							(mid -0.249642 -0.249642)
							(end -0.2794 -0.1778)
						)
						(arc
							(start -0.2794 0.1778)
							(mid -0.249642 0.249642)
							(end -0.1778 0.2794)
						)
						(arc
							(start 0.1778 0.2794)
							(mid 0.249642 0.249642)
							(end 0.2794 0.1778)
						)
						(arc
							(start 0.2794 -0.1778)
							(mid 0.249642 -0.249642)
							(end 0.1778 -0.2794)
						)
					)
					(width 0)
					(fill yes)
				)
			)
		)
	)
)
